(kicad_pcb
	(version 20241229)
	(generator "pcbnew")
	(generator_version "9.0")
	(general
		(thickness 1.61)
		(legacy_teardrops no)
	)
	(paper "A3")
	(title_block
		(title "RDIMM DDR5 Tester")
		(date "2026-05-21")
		(rev "2.2.0")
		(company "Antmicro")
		(comment 9 "footprints 469-473 of 796")
	)
	(layers
		(0 "F.Cu" signal)
		(4 "In1.Cu" power)
		(6 "In2.Cu" mixed)
		(8 "In3.Cu" power)
		(10 "In4.Cu" mixed)
		(12 "In5.Cu" power)
		(14 "In6.Cu" mixed)
		(16 "In7.Cu" power)
		(18 "In8.Cu" power)
		(20 "In9.Cu" mixed)
		(22 "In10.Cu" power)
		(2 "B.Cu" signal)
		(9 "F.Adhes" user "F.Adhesive")
		(11 "B.Adhes" user "B.Adhesive")
		(13 "F.Paste" user)
		(15 "B.Paste" user)
		(5 "F.SilkS" user "F.Silkscreen")
		(7 "B.SilkS" user "B.Silkscreen")
		(1 "F.Mask" user)
		(3 "B.Mask" user)
		(17 "Dwgs.User" user "User.Drawings")
		(19 "Cmts.User" user "User.Comments")
		(21 "Eco1.User" user "User.Eco1")
		(23 "Eco2.User" user "User.Eco2")
		(25 "Edge.Cuts" user)
		(27 "Margin" user)
		(31 "F.CrtYd" user "F.Courtyard")
		(29 "B.CrtYd" user "B.Courtyard")
		(35 "F.Fab" user)
		(33 "B.Fab" user)
	)
	(footprint "antmicro-footprints:C_0402_1005Metric"
		(layer "B.Cu")
		(at 167.6 153 90)
		(descr "Capacitor SMD 0402")
		(tags "capacitor SMD 0402")
		(property "Reference" "C4"
			(at 1.1 0.4 90)
			(layer "B.SilkS")
			(effects
				(font
					(size 0.7 0.7)
					(thickness 0.15)
				)
				(justify right bottom mirror)
			)
		)
		(property "Value" "C_100n_0402"
			(at -1.022927 -2.155213 90)
			(layer "B.Fab")
			(effects
				(font
					(size 0.7 0.7)
					(thickness 0.15)
				)
				(justify right bottom mirror)
			)
		)
		(property "Datasheet" "https://www.murata.com/products/productdetail?partno=GRM155R61H104KE14%23"
			(at 0 0 90)
			(layer "F.Fab")
			(hide yes)
			(effects
				(font
					(size 1.27 1.27)
					(thickness 0.15)
				)
			)
		)
		(property "Manufacturer" "Murata"
			(at 0 0 90)
			(unlocked yes)
			(layer "B.Fab")
			(hide yes)
			(effects
				(font
					(size 1 1)
					(thickness 0.15)
				)
				(justify mirror)
			)
		)
		(property "MPN" "GRM155R61H104KE14D"
			(at 0 0 90)
			(unlocked yes)
			(layer "B.Fab")
			(hide yes)
			(effects
				(font
					(size 1 1)
					(thickness 0.15)
				)
				(justify mirror)
			)
		)
		(property "Val" "100n"
			(at 0 0 90)
			(unlocked yes)
			(layer "B.Fab")
			(hide yes)
			(effects
				(font
					(size 1 1)
					(thickness 0.15)
				)
				(justify mirror)
			)
		)
		(property "License" "Apache-2.0"
			(at 0 0 90)
			(unlocked yes)
			(layer "B.Fab")
			(hide yes)
			(effects
				(font
					(size 1 1)
					(thickness 0.15)
				)
				(justify mirror)
			)
		)
		(property "Author" "Antmicro"
			(at 0 0 90)
			(unlocked yes)
			(layer "B.Fab")
			(hide yes)
			(effects
				(font
					(size 1 1)
					(thickness 0.15)
				)
				(justify mirror)
			)
		)
		(property "Voltage" "50V"
			(at 0 0 90)
			(unlocked yes)
			(layer "B.Fab")
			(hide yes)
			(effects
				(font
					(size 1 1)
					(thickness 0.15)
				)
				(justify mirror)
			)
		)
		(property "Dielectric" "X5R"
			(at 0 0 90)
			(unlocked yes)
			(layer "B.Fab")
			(hide yes)
			(effects
				(font
					(size 1 1)
					(thickness 0.15)
				)
				(justify mirror)
			)
		)
		(sheetname "/HyperRAM + QSPI Flash/")
		(sheetfile "hyperram-flash.kicad_sch")
		(attr smd)
		(fp_rect
			(start -0.925 0.47)
			(end 0.925 -0.47)
			(stroke
				(width 0.05)
				(type default)
			)
			(fill no)
			(layer "B.CrtYd")
		)
		(fp_line
			(start 0.504 -0.248)
			(end -0.494 -0.248)
			(stroke
				(width 0.15)
				(type solid)
			)
			(layer "B.Fab")
		)
		(fp_line
			(start -0.494 -0.248)
			(end -0.494 0.25)
			(stroke
				(width 0.15)
				(type solid)
			)
			(layer "B.Fab")
		)
		(fp_line
			(start 0.504 0.25)
			(end 0.504 -0.248)
			(stroke
				(width 0.15)
				(type solid)
			)
			(layer "B.Fab")
		)
		(fp_line
			(start -0.494 0.25)
			(end 0.504 0.25)
			(stroke
				(width 0.15)
				(type solid)
			)
			(layer "B.Fab")
		)
		(fp_text user "${REFERENCE}"
			(at -0.939 -4.599 270)
			(layer "B.Fab")
			(effects
				(font
					(size 0.7 0.7)
					(thickness 0.15)
				)
				(justify left bottom mirror)
			)
		)
		(fp_text user "License: Apache-2.0"
			(at -0.939 -5.799 270)
			(layer "B.Fab")
			(effects
				(font
					(size 0.7 0.7)
					(thickness 0.15)
				)
				(justify left bottom mirror)
			)
		)
		(fp_text user "Author: Antmicro"
			(at -0.939 -3.399 270)
			(layer "B.Fab")
			(effects
				(font
					(size 0.7 0.7)
					(thickness 0.15)
				)
				(justify left bottom mirror)
			)
		)
		(pad "1" smd roundrect
			(at -0.48 0 90)
			(size 0.59 0.64)
			(layers "B.Cu" "B.Mask" "B.Paste")
			(roundrect_rratio 0.25)
			(net 797 "+1V8")
			(pintype "passive")
		)
		(pad "2" smd roundrect
			(at 0.48 0 90)
			(size 0.59 0.64)
			(layers "B.Cu" "B.Mask" "B.Paste")
			(roundrect_rratio 0.25)
			(net 1 "GND")
			(pintype "passive")
		)
	)
	(footprint "antmicro-footprints:C_0402_1005Metric"
		(layer "B.Cu")
		(at 181.49 167.45 90)
		(descr "Capacitor SMD 0402")
		(tags "capacitor SMD 0402")
		(property "Reference" "C245"
			(at -4 -0.134 90)
			(layer "B.SilkS")
			(effects
				(font
					(size 0.7 0.7)
					(thickness 0.15)
				)
				(justify right bottom mirror)
			)
		)
		(property "Value" "C_100n_0402"
			(at -1.022927 -2.155213 90)
			(layer "B.Fab")
			(effects
				(font
					(size 0.7 0.7)
					(thickness 0.15)
				)
				(justify right bottom mirror)
			)
		)
		(property "Datasheet" "https://www.murata.com/products/productdetail?partno=GRM155R61H104KE14%23"
			(at 0 0 90)
			(layer "F.Fab")
			(hide yes)
			(effects
				(font
					(size 1.27 1.27)
					(thickness 0.15)
				)
			)
		)
		(property "Manufacturer" "Murata"
			(at 0 0 90)
			(unlocked yes)
			(layer "B.Fab")
			(hide yes)
			(effects
				(font
					(size 1 1)
					(thickness 0.15)
				)
				(justify mirror)
			)
		)
		(property "MPN" "GRM155R61H104KE14D"
			(at 0 0 90)
			(unlocked yes)
			(layer "B.Fab")
			(hide yes)
			(effects
				(font
					(size 1 1)
					(thickness 0.15)
				)
				(justify mirror)
			)
		)
		(property "Val" "100n"
			(at 0 0 90)
			(unlocked yes)
			(layer "B.Fab")
			(hide yes)
			(effects
				(font
					(size 1 1)
					(thickness 0.15)
				)
				(justify mirror)
			)
		)
		(property "License" "Apache-2.0"
			(at 0 0 90)
			(unlocked yes)
			(layer "B.Fab")
			(hide yes)
			(effects
				(font
					(size 1 1)
					(thickness 0.15)
				)
				(justify mirror)
			)
		)
		(property "Author" "Antmicro"
			(at 0 0 90)
			(unlocked yes)
			(layer "B.Fab")
			(hide yes)
			(effects
				(font
					(size 1 1)
					(thickness 0.15)
				)
				(justify mirror)
			)
		)
		(property "Voltage" "50V"
			(at 0 0 90)
			(unlocked yes)
			(layer "B.Fab")
			(hide yes)
			(effects
				(font
					(size 1 1)
					(thickness 0.15)
				)
				(justify mirror)
			)
		)
		(property "Dielectric" "X5R"
			(at 0 0 90)
			(unlocked yes)
			(layer "B.Fab")
			(hide yes)
			(effects
				(font
					(size 1 1)
					(thickness 0.15)
				)
				(justify mirror)
			)
		)
		(sheetname "/FPGA MGT Interface/")
		(sheetfile "fpga-mgt.kicad_sch")
		(attr smd)
		(fp_rect
			(start -0.925 0.47)
			(end 0.925 -0.47)
			(stroke
				(width 0.05)
				(type default)
			)
			(fill no)
			(layer "B.CrtYd")
		)
		(fp_line
			(start 0.504 -0.248)
			(end -0.494 -0.248)
			(stroke
				(width 0.15)
				(type solid)
			)
			(layer "B.Fab")
		)
		(fp_line
			(start -0.494 -0.248)
			(end -0.494 0.25)
			(stroke
				(width 0.15)
				(type solid)
			)
			(layer "B.Fab")
		)
		(fp_line
			(start 0.504 0.25)
			(end 0.504 -0.248)
			(stroke
				(width 0.15)
				(type solid)
			)
			(layer "B.Fab")
		)
		(fp_line
			(start -0.494 0.25)
			(end 0.504 0.25)
			(stroke
				(width 0.15)
				(type solid)
			)
			(layer "B.Fab")
		)
		(fp_text user "${REFERENCE}"
			(at -0.939 -4.599 270)
			(layer "B.Fab")
			(effects
				(font
					(size 0.7 0.7)
					(thickness 0.15)
				)
				(justify left bottom mirror)
			)
		)
		(fp_text user "License: Apache-2.0"
			(at -0.939 -5.799 270)
			(layer "B.Fab")
			(effects
				(font
					(size 0.7 0.7)
					(thickness 0.15)
				)
				(justify left bottom mirror)
			)
		)
		(fp_text user "Author: Antmicro"
			(at -0.939 -3.399 270)
			(layer "B.Fab")
			(effects
				(font
					(size 0.7 0.7)
					(thickness 0.15)
				)
				(justify left bottom mirror)
			)
		)
		(pad "1" smd roundrect
			(at -0.48 0 90)
			(size 0.59 0.64)
			(layers "B.Cu" "B.Mask" "B.Paste")
			(roundrect_rratio 0.25)
			(net 383 "/FPGA MGT Interface/HDMI_OUT.CLK_N")
			(pintype "passive")
		)
		(pad "2" smd roundrect
			(at 0.48 0 90)
			(size 0.59 0.64)
			(layers "B.Cu" "B.Mask" "B.Paste")
			(roundrect_rratio 0.25)
			(net 384 "/FPGA MGT Interface/HDMI_FPGA.TX_CLK_N")
			(pintype "passive")
		)
	)
	(footprint "antmicro-footprints:C_0402_1005Metric"
		(layer "B.Cu")
		(at 122.95 151.61)
		(descr "Capacitor SMD 0402")
		(tags "capacitor SMD 0402")
		(property "Reference" "C307"
			(at 2.44 1.504 0)
			(layer "B.SilkS")
			(effects
				(font
					(size 0.7 0.7)
					(thickness 0.15)
				)
				(justify right bottom mirror)
			)
		)
		(property "Value" "C_100n_0402"
			(at -1.022927 -2.155213 0)
			(layer "B.Fab")
			(effects
				(font
					(size 0.7 0.7)
					(thickness 0.15)
				)
				(justify right bottom mirror)
			)
		)
		(property "Datasheet" "https://www.murata.com/products/productdetail?partno=GRM155R61H104KE14%23"
			(at 0 0 0)
			(layer "F.Fab")
			(hide yes)
			(effects
				(font
					(size 1.27 1.27)
					(thickness 0.15)
				)
			)
		)
		(property "Manufacturer" "Murata"
			(at 0 0 0)
			(unlocked yes)
			(layer "B.Fab")
			(hide yes)
			(effects
				(font
					(size 1 1)
					(thickness 0.15)
				)
				(justify mirror)
			)
		)
		(property "MPN" "GRM155R61H104KE14D"
			(at 0 0 0)
			(unlocked yes)
			(layer "B.Fab")
			(hide yes)
			(effects
				(font
					(size 1 1)
					(thickness 0.15)
				)
				(justify mirror)
			)
		)
		(property "Val" "100n"
			(at 0 0 0)
			(unlocked yes)
			(layer "B.Fab")
			(hide yes)
			(effects
				(font
					(size 1 1)
					(thickness 0.15)
				)
				(justify mirror)
			)
		)
		(property "License" "Apache-2.0"
			(at 0 0 0)
			(unlocked yes)
			(layer "B.Fab")
			(hide yes)
			(effects
				(font
					(size 1 1)
					(thickness 0.15)
				)
				(justify mirror)
			)
		)
		(property "Author" "Antmicro"
			(at 0 0 0)
			(unlocked yes)
			(layer "B.Fab")
			(hide yes)
			(effects
				(font
					(size 1 1)
					(thickness 0.15)
				)
				(justify mirror)
			)
		)
		(property "Voltage" "50V"
			(at 0 0 0)
			(unlocked yes)
			(layer "B.Fab")
			(hide yes)
			(effects
				(font
					(size 1 1)
					(thickness 0.15)
				)
				(justify mirror)
			)
		)
		(property "Dielectric" "X5R"
			(at 0 0 0)
			(unlocked yes)
			(layer "B.Fab")
			(hide yes)
			(effects
				(font
					(size 1 1)
					(thickness 0.15)
				)
				(justify mirror)
			)
		)
		(sheetname "/FPGA MGT Interface/")
		(sheetfile "fpga-mgt.kicad_sch")
		(attr smd)
		(fp_rect
			(start -0.925 0.47)
			(end 0.925 -0.47)
			(stroke
				(width 0.05)
				(type default)
			)
			(fill no)
			(layer "B.CrtYd")
		)
		(fp_line
			(start -0.494 -0.248)
			(end -0.494 0.25)
			(stroke
				(width 0.15)
				(type solid)
			)
			(layer "B.Fab")
		)
		(fp_line
			(start -0.494 0.25)
			(end 0.504 0.25)
			(stroke
				(width 0.15)
				(type solid)
			)
			(layer "B.Fab")
		)
		(fp_line
			(start 0.504 -0.248)
			(end -0.494 -0.248)
			(stroke
				(width 0.15)
				(type solid)
			)
			(layer "B.Fab")
		)
		(fp_line
			(start 0.504 0.25)
			(end 0.504 -0.248)
			(stroke
				(width 0.15)
				(type solid)
			)
			(layer "B.Fab")
		)
		(fp_text user "License: Apache-2.0"
			(at -0.939 -5.799 180)
			(layer "B.Fab")
			(effects
				(font
					(size 0.7 0.7)
					(thickness 0.15)
				)
				(justify left bottom mirror)
			)
		)
		(fp_text user "${REFERENCE}"
			(at -0.939 -4.599 180)
			(layer "B.Fab")
			(effects
				(font
					(size 0.7 0.7)
					(thickness 0.15)
				)
				(justify left bottom mirror)
			)
		)
		(fp_text user "Author: Antmicro"
			(at -0.939 -3.399 180)
			(layer "B.Fab")
			(effects
				(font
					(size 0.7 0.7)
					(thickness 0.15)
				)
				(justify left bottom mirror)
			)
		)
		(pad "1" smd roundrect
			(at -0.48 0)
			(size 0.59 0.64)
			(layers "B.Cu" "B.Mask" "B.Paste")
			(roundrect_rratio 0.25)
			(net 380 "/FPGA MGT Interface/HDMI_IN.D0_P")
			(pintype "passive")
		)
		(pad "2" smd roundrect
			(at 0.48 0)
			(size 0.59 0.64)
			(layers "B.Cu" "B.Mask" "B.Paste")
			(roundrect_rratio 0.25)
			(net 653 "/FPGA MGT Interface/HDMI_FPGA.RX0_P")
			(pintype "passive")
		)
	)
	(footprint "antmicro-footprints:C_0402_1005Metric"
		(layer "B.Cu")
		(at 255.724499 132.214 90)
		(descr "Capacitor SMD 0402")
		(tags "capacitor SMD 0402")
		(property "Reference" "C195"
			(at 1.414 0.375501 90)
			(layer "B.SilkS")
			(effects
				(font
					(size 0.7 0.7)
					(thickness 0.15)
				)
				(justify right bottom mirror)
			)
		)
		(property "Value" "C_100n_0402"
			(at -1.022927 -2.155213 90)
			(layer "B.Fab")
			(effects
				(font
					(size 0.7 0.7)
					(thickness 0.15)
				)
				(justify right bottom mirror)
			)
		)
		(property "Datasheet" "https://www.murata.com/products/productdetail?partno=GRM155R61H104KE14%23"
			(at 0 0 90)
			(layer "F.Fab")
			(hide yes)
			(effects
				(font
					(size 1.27 1.27)
					(thickness 0.15)
				)
			)
		)
		(property "Manufacturer" "Murata"
			(at 0 0 90)
			(unlocked yes)
			(layer "B.Fab")
			(hide yes)
			(effects
				(font
					(size 1 1)
					(thickness 0.15)
				)
				(justify mirror)
			)
		)
		(property "MPN" "GRM155R61H104KE14D"
			(at 0 0 90)
			(unlocked yes)
			(layer "B.Fab")
			(hide yes)
			(effects
				(font
					(size 1 1)
					(thickness 0.15)
				)
				(justify mirror)
			)
		)
		(property "Val" "100n"
			(at 0 0 90)
			(unlocked yes)
			(layer "B.Fab")
			(hide yes)
			(effects
				(font
					(size 1 1)
					(thickness 0.15)
				)
				(justify mirror)
			)
		)
		(property "License" "Apache-2.0"
			(at 0 0 90)
			(unlocked yes)
			(layer "B.Fab")
			(hide yes)
			(effects
				(font
					(size 1 1)
					(thickness 0.15)
				)
				(justify mirror)
			)
		)
		(property "Author" "Antmicro"
			(at 0 0 90)
			(unlocked yes)
			(layer "B.Fab")
			(hide yes)
			(effects
				(font
					(size 1 1)
					(thickness 0.15)
				)
				(justify mirror)
			)
		)
		(property "Voltage" "50V"
			(at 0 0 90)
			(unlocked yes)
			(layer "B.Fab")
			(hide yes)
			(effects
				(font
					(size 1 1)
					(thickness 0.15)
				)
				(justify mirror)
			)
		)
		(property "Dielectric" "X5R"
			(at 0 0 90)
			(unlocked yes)
			(layer "B.Fab")
			(hide yes)
			(effects
				(font
					(size 1 1)
					(thickness 0.15)
				)
				(justify mirror)
			)
		)
		(sheetname "/Supply/")
		(sheetfile "supply.kicad_sch")
		(attr smd)
		(fp_rect
			(start -0.925 0.47)
			(end 0.925 -0.47)
			(stroke
				(width 0.05)
				(type default)
			)
			(fill no)
			(layer "B.CrtYd")
		)
		(fp_line
			(start 0.504 -0.248)
			(end -0.494 -0.248)
			(stroke
				(width 0.15)
				(type solid)
			)
			(layer "B.Fab")
		)
		(fp_line
			(start -0.494 -0.248)
			(end -0.494 0.25)
			(stroke
				(width 0.15)
				(type solid)
			)
			(layer "B.Fab")
		)
		(fp_line
			(start 0.504 0.25)
			(end 0.504 -0.248)
			(stroke
				(width 0.15)
				(type solid)
			)
			(layer "B.Fab")
		)
		(fp_line
			(start -0.494 0.25)
			(end 0.504 0.25)
			(stroke
				(width 0.15)
				(type solid)
			)
			(layer "B.Fab")
		)
		(fp_text user "Author: Antmicro"
			(at -0.939 -3.399 270)
			(layer "B.Fab")
			(effects
				(font
					(size 0.7 0.7)
					(thickness 0.15)
				)
				(justify left bottom mirror)
			)
		)
		(fp_text user "${REFERENCE}"
			(at -0.939 -4.599 270)
			(layer "B.Fab")
			(effects
				(font
					(size 0.7 0.7)
					(thickness 0.15)
				)
				(justify left bottom mirror)
			)
		)
		(fp_text user "License: Apache-2.0"
			(at -0.939 -5.799 270)
			(layer "B.Fab")
			(effects
				(font
					(size 0.7 0.7)
					(thickness 0.15)
				)
				(justify left bottom mirror)
			)
		)
		(pad "1" smd roundrect
			(at -0.48 0 90)
			(size 0.59 0.64)
			(layers "B.Cu" "B.Mask" "B.Paste")
			(roundrect_rratio 0.25)
			(net 1 "GND")
			(pintype "passive")
		)
		(pad "2" smd roundrect
			(at 0.48 0 90)
			(size 0.59 0.64)
			(layers "B.Cu" "B.Mask" "B.Paste")
			(roundrect_rratio 0.25)
			(net 38 "+3V3_AON")
			(pintype "passive")
		)
	)
	(footprint "antmicro-footprints:C_0402_1005Metric_EIA"
		(layer "B.Cu")
		(at 185 158.5 90)
		(descr "Capacitor SMD 0402 (1005 Metric), square (rectangular) end terminal, IPC_7351 nominal, (Body size source: IPC-SM-782 page 76, https://www.pcb-3d.com/wordpress/wp-content/uploads/ipc-sm-782a_amendment_1_and_2.pdf)")
		(tags "capacitor 0402")
		(property "Reference" "C52"
			(at 9.8 -30.625 90)
			(layer "B.SilkS")
			(effects
				(font
					(size 0.7 0.7)
					(thickness 0.15)
				)
				(justify right bottom mirror)
			)
		)
		(property "Value" "C_1u_25V_0402"
			(at 0 -1.169 90)
			(layer "B.Fab")
			(effects
				(font
					(size 0.7 0.7)
					(thickness 0.15)
				)
				(justify right bottom mirror)
			)
		)
		(property "Datasheet" "https://www.murata.com/products/productdetail?partno=GRM155R61E105KE11%23"
			(at 0 0 90)
			(layer "F.Fab")
			(hide yes)
			(effects
				(font
					(size 1.27 1.27)
					(thickness 0.15)
				)
			)
		)
		(property "MPN" "GRM155R61E105KE11J"
			(at 0 0 90)
			(unlocked yes)
			(layer "B.Fab")
			(hide yes)
			(effects
				(font
					(size 1 1)
					(thickness 0.15)
				)
				(justify mirror)
			)
		)
		(property "Manufacturer" "Murata"
			(at 0 0 90)
			(unlocked yes)
			(layer "B.Fab")
			(hide yes)
			(effects
				(font
					(size 1 1)
					(thickness 0.15)
				)
				(justify mirror)
			)
		)
		(property "License" "Apache-2.0"
			(at 0 0 90)
			(unlocked yes)
			(layer "B.Fab")
			(hide yes)
			(effects
				(font
					(size 1 1)
					(thickness 0.15)
				)
				(justify mirror)
			)
		)
		(property "Author" "Antmicro"
			(at 0 0 90)
			(unlocked yes)
			(layer "B.Fab")
			(hide yes)
			(effects
				(font
					(size 1 1)
					(thickness 0.15)
				)
				(justify mirror)
			)
		)
		(property "Val" "1u"
			(at 0 0 90)
			(unlocked yes)
			(layer "B.Fab")
			(hide yes)
			(effects
				(font
					(size 1 1)
					(thickness 0.15)
				)
				(justify mirror)
			)
		)
		(property "Voltage" "25V"
			(at 0 0 90)
			(unlocked yes)
			(layer "B.Fab")
			(hide yes)
			(effects
				(font
					(size 1 1)
					(thickness 0.15)
				)
				(justify mirror)
			)
		)
		(property "Dielectric" "X5R"
			(at 0 0 90)
			(unlocked yes)
			(layer "B.Fab")
			(hide yes)
			(effects
				(font
					(size 1 1)
					(thickness 0.15)
				)
				(justify mirror)
			)
		)
		(sheetname "/FPGA power/")
		(sheetfile "fpga-power.kicad_sch")
		(attr smd)
		(fp_rect
			(start -0.95 0.45)
			(end 0.95 -0.45)
			(stroke
				(width 0.05)
				(type default)
			)
			(fill no)
			(layer "B.CrtYd")
		)
		(fp_line
			(start 0.498 -0.248)
			(end -0.5 -0.248)
			(stroke
				(width 0.15)
				(type solid)
			)
			(layer "B.Fab")
		)
		(fp_line
			(start -0.5 -0.248)
			(end -0.5 0.25)
			(stroke
				(width 0.15)
				(type solid)
			)
			(layer "B.Fab")
		)
		(fp_line
			(start 0.498 0.25)
			(end 0.498 -0.248)
			(stroke
				(width 0.15)
				(type solid)
			)
			(layer "B.Fab")
		)
		(fp_line
			(start -0.5 0.25)
			(end 0.498 0.25)
			(stroke
				(width 0.15)
				(type solid)
			)
			(layer "B.Fab")
		)
		(fp_text user "License: Apache-2.0"
			(at -0.9656 -4.369 270)
			(layer "B.Fab")
			(effects
				(font
					(size 0.7 0.7)
					(thickness 0.15)
				)
				(justify left bottom mirror)
			)
		)
		(fp_text user "Author: Antmicro"
			(at -0.9656 -5.569 270)
			(layer "B.Fab")
			(effects
				(font
					(size 0.7 0.7)
					(thickness 0.15)
				)
				(justify left bottom mirror)
			)
		)
		(fp_text user "${REFERENCE}"
			(at -0.9656 -3.169 270)
			(layer "B.Fab")
			(effects
				(font
					(size 0.7 0.7)
					(thickness 0.15)
				)
				(justify left bottom mirror)
			)
		)
		(pad "1" smd roundrect
			(at -0.5 0)
			(size 0.6 0.6)
			(layers "B.Cu" "B.Mask" "B.Paste")
			(roundrect_rratio 0.25)
			(net 1 "GND")
			(pintype "passive")
		)
		(pad "2" smd roundrect
			(at 0.498 0 90)
			(size 0.6 0.6)
			(layers "B.Cu" "B.Mask" "B.Paste")
			(roundrect_rratio 0.25)
			(net 553 "+0V85")
			(pintype "passive")
		)
	)
)
